# TIMECARD (Time Appliance Project (Time Card)) — schematic netlist excerpt (pin names and nets, part order shuffled) for the footprints in the layout excerpt that follows; sources: Cadence DE-HDL packaged netlist, KiCad conversion of R4006-B0001-02_R01.brd

J10  G200_10283_01  pkg S_M_DIL_2X5_P100_V1  page 24
  \1\  = FT4232_CHD_TX
  \2\  = DBG_UART_MAC_RX
  \3\  = FT4232_CHD_TX
  \4\  = DBG_UART_GPS_RXD
  \5\  = FT4232_CHD_RX
  \6\  = DBG_UART_MAC_TX
  \7\  = FT4232_CHD_RX
  \8\  = DBG_UART_GPS_TXD
  \9\  = SG
  \10\  = FPGA_CFG_INIT_N

(kicad_pcb
	(version 20260206)
	(generator "pcbnew")
	(generator_version "10.0")
	(general
		(thickness 1.6)
		(legacy_teardrops no)
	)
	(paper "A4")
	(title_block
		(title "timecard-production-celestica-r4006 — R4006-B0001-02_R01.brd")
		(comment 1 "Time Appliance Project (Time Card) / footprint 356 of 1113 (J10), pads 1-10 of 10")
	)
	(layers
		(0 "F.Cu" signal "TOP")
		(4 "In1.Cu" signal "L02_GND1")
		(6 "In2.Cu" signal "L03_SIG1")
		(8 "In3.Cu" signal "L04_GND2")
		(10 "In4.Cu" signal "L05_VCC1")
		(12 "In5.Cu" signal "L06_VCC2")
		(14 "In6.Cu" signal "L07_GND3")
		(16 "In7.Cu" signal "L08_SIG2")
		(18 "In8.Cu" signal "L09_GND4")
		(2 "B.Cu" signal "BOTTOM")
		(9 "F.Adhes" user "F.Adhesive")
		(11 "B.Adhes" user "B.Adhesive")
		(13 "F.Paste" user "Package Geometry/Pastemask Top")
		(15 "B.Paste" user "Package Geometry/Pastemask Bottom")
		(5 "F.SilkS" user "Ref Des/Silkscreen Top")
		(7 "B.SilkS" user "Ref Des/Silkscreen Bottom")
		(1 "F.Mask" user "Board Geometry/Soldermask Top")
		(3 "B.Mask" user "Board Geometry/Soldermask Bottom")
		(17 "Dwgs.User" user "User.Drawings")
		(19 "Cmts.User" user "User.Comments")
		(21 "Eco1.User" user "User.Eco1")
		(23 "Eco2.User" user "User.Eco2")
		(25 "Edge.Cuts" user "Board Geometry/Outline")
		(27 "Margin" user)
		(31 "F.CrtYd" user "Package Geometry/Place Bound Top")
		(29 "B.CrtYd" user "Package Geometry/Place Bound Bottom")
		(35 "F.Fab" user "Ref Des/Assembly Top")
		(33 "B.Fab" user "Ref Des/Assembly Bottom")
	)
	(footprint ""
		(layer "F.Cu")
		(at 155.4734 -71.501 90)
		(property "Reference" "J10"
			(at 7.07263 0.2286 0)
			(unlocked yes)
			(layer "F.SilkS")
			(effects
				(font
					(size 0.7874 0.5842)
					(thickness 0.1524)
				)
			)
		)
		(property "Value" ""
			(at 0 0 90)
			(layer "F.Fab")
			(effects
				(font
					(size 1.27 1.27)
				)
			)
		)
		(property "User Part Number" "PARTNUM*"
			(at 0.191262 6.403086 90)
			(unlocked yes)
			(layer "Cmts.User")
			(hide yes)
			(effects
				(font
					(size 0.7874 0.5842)
					(thickness 0.1524)
				)
			)
		)
		(property "Device Type" "G200_10283_01-G200-10283-01"
			(at 0.241808 5.437378 90)
			(unlocked yes)
			(layer "F.Fab")
			(hide yes)
			(effects
				(font
					(size 0.7874 0.5842)
					(thickness 0.1524)
				)
			)
		)
		(duplicate_pad_numbers_are_jumpers no)
		(pad "1" smd rect
			(at -5.08 2.605024 90)
			(size 1.27 3.556)
			(layers "F.Cu" "F.Mask" "F.Paste")
			(net "FT4232_CHD_TX")
		)
		(pad "2" smd rect
			(at -5.08 -2.605024 90)
			(size 1.27 3.556)
			(layers "F.Cu" "F.Mask" "F.Paste")
			(net "DBG_UART_MAC_RX")
		)
		(pad "3" smd rect
			(at -2.54 2.605024 90)
			(size 1.27 3.556)
			(layers "F.Cu" "F.Mask" "F.Paste")
			(net "FT4232_CHD_TX")
		)
		(pad "4" smd rect
			(at -2.54 -2.605024 90)
			(size 1.27 3.556)
			(layers "F.Cu" "F.Mask" "F.Paste")
			(net "DBG_UART_GPS_RXD")
		)
		(pad "5" smd rect
			(at 0 2.605024 90)
			(size 1.27 3.556)
			(layers "F.Cu" "F.Mask" "F.Paste")
			(net "FT4232_CHD_RX")
		)
		(pad "6" smd rect
			(at 0 -2.605024 90)
			(size 1.27 3.556)
			(layers "F.Cu" "F.Mask" "F.Paste")
			(net "DBG_UART_MAC_TX")
		)
		(pad "7" smd rect
			(at 2.54 2.605024 90)
			(size 1.27 3.556)
			(layers "F.Cu" "F.Mask" "F.Paste")
			(net "FT4232_CHD_RX")
		)
		(pad "8" smd rect
			(at 2.54 -2.605024 90)
			(size 1.27 3.556)
			(layers "F.Cu" "F.Mask" "F.Paste")
			(net "DBG_UART_GPS_TXD")
		)
		(pad "9" smd rect
			(at 5.08 2.605024 90)
			(size 1.27 3.556)
			(layers "F.Cu" "F.Mask" "F.Paste")
			(net "SG")
		)
		(pad "10" smd rect
			(at 5.08 -2.605024 90)
			(size 1.27 3.556)
			(layers "F.Cu" "F.Mask" "F.Paste")
			(net "FPGA_CFG_INIT_N")
		)
	)
)
